# TIMECARD (Time Appliance Project (Time Card)) — schematic netlist excerpt (pin names and nets, part order shuffled) for the footprints in the layout excerpt that follows; sources: Cadence DE-HDL packaged netlist, KiCad conversion of R4006-B0001-02_R01.brd

TP132  TP_PIONT  pkg TP010CT020B030_PTH  page 25 : \1\ = IO_L20P_34
C41  CAPACITOR  0.1UF 25V 10%  pkg SMC_0402R_H022  page 32 : \1\ = VIN_XP5R0V ; \2\ = SG

(kicad_pcb
	(version 20260206)
	(generator "pcbnew")
	(generator_version "10.0")
	(general
		(thickness 1.6)
		(legacy_teardrops no)
	)
	(paper "A4")
	(title_block
		(title "timecard-production-celestica-r4006 — R4006-B0001-02_R01.brd")
		(comment 1 "Time Appliance Project (Time Card) / footprints 628-629 of 1113")
	)
	(layers
		(0 "F.Cu" signal "TOP")
		(4 "In1.Cu" signal "L02_GND1")
		(6 "In2.Cu" signal "L03_SIG1")
		(8 "In3.Cu" signal "L04_GND2")
		(10 "In4.Cu" signal "L05_VCC1")
		(12 "In5.Cu" signal "L06_VCC2")
		(14 "In6.Cu" signal "L07_GND3")
		(16 "In7.Cu" signal "L08_SIG2")
		(18 "In8.Cu" signal "L09_GND4")
		(2 "B.Cu" signal "BOTTOM")
		(9 "F.Adhes" user "F.Adhesive")
		(11 "B.Adhes" user "B.Adhesive")
		(13 "F.Paste" user "Package Geometry/Pastemask Top")
		(15 "B.Paste" user "Package Geometry/Pastemask Bottom")
		(5 "F.SilkS" user "Ref Des/Silkscreen Top")
		(7 "B.SilkS" user "Ref Des/Silkscreen Bottom")
		(1 "F.Mask" user "Board Geometry/Soldermask Top")
		(3 "B.Mask" user "Board Geometry/Soldermask Bottom")
		(17 "Dwgs.User" user "User.Drawings")
		(19 "Cmts.User" user "User.Comments")
		(21 "Eco1.User" user "User.Eco1")
		(23 "Eco2.User" user "User.Eco2")
		(25 "Edge.Cuts" user "Board Geometry/Outline")
		(27 "Margin" user)
		(31 "F.CrtYd" user "Package Geometry/Place Bound Top")
		(29 "B.CrtYd" user "Package Geometry/Place Bound Bottom")
		(35 "F.Fab" user "Ref Des/Assembly Top")
		(33 "B.Fab" user "Ref Des/Assembly Bottom")
	)
	(footprint ""
		(layer "F.Cu")
		(at 120.346978 -39.323264 90)
		(property "Reference" "TP132"
			(at 0 0 90)
			(layer "F.SilkS")
			(hide yes)
			(effects
				(font
					(size 1.27 1.27)
				)
			)
		)
		(property "Value" ""
			(at 0 0 90)
			(layer "F.Fab")
			(effects
				(font
					(size 1.27 1.27)
				)
			)
		)
		(property "Device Type" "TP_PIONT-TP010CT020B030_PTH-TPA"
			(at -1.341882 0.996696 90)
			(unlocked yes)
			(layer "F.Fab")
			(hide yes)
			(effects
				(font
					(size 0.7874 0.5842)
					(thickness 0.1524)
				)
				(justify left)
			)
		)
		(duplicate_pad_numbers_are_jumpers no)
		(fp_poly
			(pts
				(arc
					(start 0 0.889)
					(mid 0 -0.889)
					(end 0 0.889)
				)
			)
			(stroke
				(width 0)
				(type default)
			)
			(fill no)
			(layer "B.CrtYd")
		)
		(fp_poly
			(pts
				(arc
					(start 0 0.889)
					(mid 0 -0.889)
					(end 0 0.889)
				)
			)
			(stroke
				(width 0)
				(type default)
			)
			(fill no)
			(layer "F.CrtYd")
		)
		(pad "1" thru_hole circle
			(at 0 0 90)
			(size 0.508 0.508)
			(drill 0.254)
			(layers "*.Cu" "*.Mask")
			(remove_unused_layers no)
			(net "IO_L20P_34")
			(clearance 0.1016)
			(padstack
				(mode front_inner_back)
				(layer "Inner"
					(shape circle)
					(size 0.508 0.508)
					(clearance 0.1016)
				)
				(layer "B.Cu"
					(shape circle)
					(size 0.762 0.762)
					(clearance -0.0254)
				)
			)
		)
	)
	(footprint ""
		(layer "F.Cu")
		(at 42.9514 -97.5614)
		(property "Reference" "C41"
			(at 0.635 4.58597 0)
			(unlocked yes)
			(layer "F.SilkS")
			(effects
				(font
					(size 0.7874 0.5842)
					(thickness 0.1524)
				)
			)
		)
		(property "Value" "VAL*"
			(at 0.0762 2.067306 0)
			(unlocked yes)
			(layer "F.Fab")
			(hide yes)
			(effects
				(font
					(size 0.7874 0.5842)
					(thickness 0.1524)
				)
			)
		)
		(property "Device Type" "CAPACITOR-G105-0B104-EK,0.1UF,A"
			(at 0.0508 1.127506 0)
			(unlocked yes)
			(layer "F.Fab")
			(hide yes)
			(effects
				(font
					(size 0.7874 0.5842)
					(thickness 0.1524)
				)
			)
		)
		(property "User Part Number" "PARTNUM*"
			(at 0.1016 4.023106 0)
			(unlocked yes)
			(layer "Cmts.User")
			(hide yes)
			(effects
				(font
					(size 0.7874 0.5842)
					(thickness 0.1524)
				)
			)
		)
		(property "Tolerance" "TOL*"
			(at 0.0762 3.032506 0)
			(unlocked yes)
			(layer "Cmts.User")
			(hide yes)
			(effects
				(font
					(size 0.7874 0.5842)
					(thickness 0.1524)
				)
			)
		)
		(duplicate_pad_numbers_are_jumpers no)
		(fp_line
			(start -1.143 -0.5588)
			(end -1.143 0.5588)
			(stroke
				(width 0.1)
				(type default)
			)
			(layer "F.SilkS")
		)
		(fp_line
			(start -1.143 0.5588)
			(end 1.143 0.5588)
			(stroke
				(width 0.1)
				(type default)
			)
			(layer "F.SilkS")
		)
		(fp_line
			(start 1.143 -0.5588)
			(end -1.143 -0.5588)
			(stroke
				(width 0.1)
				(type default)
			)
			(layer "F.SilkS")
		)
		(fp_line
			(start 1.143 0.5588)
			(end 1.143 -0.5588)
			(stroke
				(width 0.1)
				(type default)
			)
			(layer "F.SilkS")
		)
		(fp_rect
			(start 1.143 -0.5588)
			(end -1.143 0.5588)
			(stroke
				(width 0)
				(type default)
			)
			(fill no)
			(layer "F.CrtYd")
		)
		(fp_line
			(start -0.508 -0.3048)
			(end -0.508 0.3048)
			(stroke
				(width 0.1)
				(type default)
			)
			(layer "F.Fab")
		)
		(fp_line
			(start -0.508 0.3048)
			(end 0.508 0.3048)
			(stroke
				(width 0.1)
				(type default)
			)
			(layer "F.Fab")
		)
		(fp_line
			(start 0.508 -0.3048)
			(end -0.508 -0.3048)
			(stroke
				(width 0.1)
				(type default)
			)
			(layer "F.Fab")
		)
		(fp_line
			(start 0.508 0.3048)
			(end 0.508 -0.3048)
			(stroke
				(width 0.1)
				(type default)
			)
			(layer "F.Fab")
		)
		(pad "1" smd rect
			(at -0.5334 0)
			(size 0.7112 0.6096)
			(layers "F.Cu" "F.Mask" "F.Paste")
			(net "VIN_XP5R0V")
		)
		(pad "2" smd rect
			(at 0.5334 0)
			(size 0.7112 0.6096)
			(layers "F.Cu" "F.Mask" "F.Paste")
			(net "SG")
		)
		(zone
			(layer "F.Cu")
			(hatch none 0.5)
			(connect_pads
				(clearance 0)
			)
			(min_thickness 0.25)
			(keepout
				(tracks allowed)
				(vias not_allowed)
				(pads allowed)
				(copperpour not_allowed)
				(footprints allowed)
			)
			(placement
				(enabled no)
				(sheetname "")
			)
			(fill
				(thermal_gap 0.5)
				(thermal_bridge_width 0.5)
				(island_removal_mode 0)
			)
			(polygon
				(pts
					(xy 43.0276 -97.8662) (xy 42.8752 -97.8662) (xy 42.8752 -97.2566) (xy 43.0276 -97.2566)
				)
			)
		)
	)
)
